(kicad_pcb
	(version 20260206)
	(generator "pcbnew")
	(generator_version "10.0")
	(general
		(thickness 1.6)
		(legacy_teardrops no)
	)
	(paper "A4")
	(title_block
		(title "01162023_DA0F0TEBIF0_F0T_Expander_BD_F_brd_V02_OCP.brd")
		(comment 1 "Grand Teton / footprints 3897-3903 of 9728")
	)
	(layers
		(0 "F.Cu" signal "TOP")
		(4 "In1.Cu" signal "GND")
		(6 "In2.Cu" signal "VCC")
		(8 "In3.Cu" signal "VCC1")
		(10 "In4.Cu" signal "GND1")
		(12 "In5.Cu" signal "IN1")
		(14 "In6.Cu" signal "GND2")
		(16 "In7.Cu" signal "IN2")
		(18 "In8.Cu" signal "GND3")
		(20 "In9.Cu" signal "IN3")
		(22 "In10.Cu" signal "GND4")
		(24 "In11.Cu" signal "IN4")
		(26 "In12.Cu" signal "GND5")
		(28 "In13.Cu" signal "IN5")
		(30 "In14.Cu" signal "GND6")
		(32 "In15.Cu" signal "IN6")
		(34 "In16.Cu" signal "GND7")
		(2 "B.Cu" signal "BOTTOM")
		(9 "F.Adhes" user "F.Adhesive")
		(11 "B.Adhes" user "B.Adhesive")
		(13 "F.Paste" user "Package Geometry/Pastemask Top")
		(15 "B.Paste" user "Package Geometry/Pastemask Bottom")
		(5 "F.SilkS" user "Ref Des/Silkscreen Top")
		(7 "B.SilkS" user "Ref Des/Silkscreen Bottom")
		(1 "F.Mask" user "Board Geometry/Soldermask Top")
		(3 "B.Mask" user "Board Geometry/Soldermask Bottom")
		(17 "Dwgs.User" user "User.Drawings")
		(19 "Cmts.User" user "User.Comments")
		(21 "Eco1.User" user "User.Eco1")
		(23 "Eco2.User" user "User.Eco2")
		(25 "Edge.Cuts" user "Board Geometry/Outline")
		(27 "Margin" user)
		(31 "F.CrtYd" user "Package Geometry/Place Bound Top")
		(29 "B.CrtYd" user "Package Geometry/Place Bound Bottom")
		(35 "F.Fab" user "Ref Des/Assembly Top")
		(33 "B.Fab" user "Ref Des/Assembly Bottom")
	)
	(footprint ""
		(layer "F.Cu")
		(at 241.3254 -216.408 90)
		(property "Reference" "C4434"
			(at 0 0 90)
			(layer "F.SilkS")
			(hide yes)
			(effects
				(font
					(size 1.27 1.27)
				)
			)
		)
		(property "Value" ""
			(at 0 0 90)
			(layer "F.Fab")
			(effects
				(font
					(size 1.27 1.27)
				)
			)
		)
		(duplicate_pad_numbers_are_jumpers no)
		(fp_line
			(start 0.7874 -0.4064)
			(end 0.7874 0.4064)
			(stroke
				(width 0.1524)
				(type default)
			)
			(layer "F.SilkS")
		)
		(fp_line
			(start -0.7874 -0.4064)
			(end 0.7874 -0.4064)
			(stroke
				(width 0.1524)
				(type default)
			)
			(layer "F.SilkS")
		)
		(fp_line
			(start 0.7874 0.4064)
			(end -0.7874 0.4064)
			(stroke
				(width 0.1524)
				(type default)
			)
			(layer "F.SilkS")
		)
		(fp_line
			(start -0.7874 0.4064)
			(end -0.7874 -0.4064)
			(stroke
				(width 0.1524)
				(type default)
			)
			(layer "F.SilkS")
		)
		(fp_line
			(start -0.12065 -0.305054)
			(end -0.12065 -0.2794)
			(stroke
				(width 0.1)
				(type default)
			)
			(layer "F.Fab")
		)
		(fp_line
			(start -0.67945 -0.305054)
			(end -0.12065 -0.305054)
			(stroke
				(width 0.1)
				(type default)
			)
			(layer "F.Fab")
		)
		(fp_line
			(start 0.67945 -0.3048)
			(end 0.67945 0.3048)
			(stroke
				(width 0.1)
				(type default)
			)
			(layer "F.Fab")
		)
		(fp_line
			(start 0.12065 -0.3048)
			(end 0.67945 -0.3048)
			(stroke
				(width 0.1)
				(type default)
			)
			(layer "F.Fab")
		)
		(fp_line
			(start 0.12065 -0.2794)
			(end 0.12065 -0.3048)
			(stroke
				(width 0.1)
				(type default)
			)
			(layer "F.Fab")
		)
		(fp_line
			(start -0.12065 -0.2794)
			(end 0.12065 -0.2794)
			(stroke
				(width 0.1)
				(type default)
			)
			(layer "F.Fab")
		)
		(fp_line
			(start 0.120396 0.2794)
			(end -0.12065 0.2794)
			(stroke
				(width 0.1)
				(type default)
			)
			(layer "F.Fab")
		)
		(fp_line
			(start -0.12065 0.2794)
			(end -0.12065 0.3048)
			(stroke
				(width 0.1)
				(type default)
			)
			(layer "F.Fab")
		)
		(fp_line
			(start 0.67945 0.3048)
			(end 0.120396 0.3048)
			(stroke
				(width 0.1)
				(type default)
			)
			(layer "F.Fab")
		)
		(fp_line
			(start 0.120396 0.3048)
			(end 0.120396 0.2794)
			(stroke
				(width 0.1)
				(type default)
			)
			(layer "F.Fab")
		)
		(fp_line
			(start -0.12065 0.3048)
			(end -0.67945 0.3048)
			(stroke
				(width 0.1)
				(type default)
			)
			(layer "F.Fab")
		)
		(fp_line
			(start -0.67945 0.3048)
			(end -0.67945 -0.305054)
			(stroke
				(width 0.1)
				(type default)
			)
			(layer "F.Fab")
		)
		(pad "1" smd circle
			(at -0.40005 0 90)
			(size 0 0)
			(layers "F.Cu" "F.Mask" "F.Paste")
			(net "P1V8_PLL0_PEX0_SCALED")
		)
		(pad "2" smd circle
			(at 0.40005 0 90)
			(size 0 0)
			(layers "F.Cu" "F.Mask" "F.Paste")
			(net "GND")
		)
	)
	(footprint ""
		(layer "F.Cu")
		(at 275.992336 -29.139642 180)
		(property "Reference" "C501"
			(at 0 0 180)
			(layer "F.SilkS")
			(hide yes)
			(effects
				(font
					(size 1.27 1.27)
				)
			)
		)
		(property "Value" ""
			(at 0 0 180)
			(layer "F.Fab")
			(effects
				(font
					(size 1.27 1.27)
				)
			)
		)
		(duplicate_pad_numbers_are_jumpers no)
		(fp_line
			(start 0.299974 0.150114)
			(end -0.299974 0.150114)
			(stroke
				(width 0.1)
				(type default)
			)
			(layer "F.Fab")
		)
		(fp_line
			(start 0.299974 -0.150114)
			(end 0.299974 0.150114)
			(stroke
				(width 0.1)
				(type default)
			)
			(layer "F.Fab")
		)
		(fp_line
			(start -0.299974 0.150114)
			(end -0.299974 -0.150114)
			(stroke
				(width 0.1)
				(type default)
			)
			(layer "F.Fab")
		)
		(fp_line
			(start -0.299974 -0.150114)
			(end 0.299974 -0.150114)
			(stroke
				(width 0.1)
				(type default)
			)
			(layer "F.Fab")
		)
		(pad "1" smd rect
			(at -0.2667 0 180)
			(size 0.3048 0.381)
			(layers "F.Cu" "F.Mask" "F.Paste")
			(net "P5E_PEX2_STN2_TX_DP<40>")
		)
		(pad "2" smd rect
			(at 0.2667 0 180)
			(size 0.3048 0.381)
			(layers "F.Cu" "F.Mask" "F.Paste")
			(net "P5E_PEX2_STN2_TX_C_DP<40>")
		)
	)
	(footprint ""
		(layer "F.Cu")
		(at 256.47396 -26.31186 -90)
		(property "Reference" "U412"
			(at -0.00254 -2.35331 90)
			(unlocked yes)
			(layer "F.SilkS")
			(effects
				(font
					(size 0.7874 0.5842)
					(thickness 0.1524)
				)
			)
		)
		(property "Value" ""
			(at 0 0 270)
			(layer "F.Fab")
			(effects
				(font
					(size 1.27 1.27)
				)
			)
		)
		(duplicate_pad_numbers_are_jumpers no)
		(fp_line
			(start -1.949958 1.610106)
			(end -1.949958 -1.610106)
			(stroke
				(width 0.1524)
				(type default)
			)
			(layer "F.SilkS")
		)
		(fp_line
			(start 1.949958 1.610106)
			(end -1.949958 1.610106)
			(stroke
				(width 0.1524)
				(type default)
			)
			(layer "F.SilkS")
		)
		(fp_line
			(start 1.949958 -1.560068)
			(end 1.949958 1.610106)
			(stroke
				(width 0.1524)
				(type default)
			)
			(layer "F.SilkS")
		)
		(fp_line
			(start -1.949958 -1.610106)
			(end 1.949958 -1.610106)
			(stroke
				(width 0.1524)
				(type default)
			)
			(layer "F.SilkS")
		)
		(fp_line
			(start -0.750062 1.560068)
			(end -0.750062 -1.560068)
			(stroke
				(width 0.1)
				(type default)
			)
			(layer "F.Fab")
		)
		(fp_line
			(start 0.750062 1.560068)
			(end -0.750062 1.560068)
			(stroke
				(width 0.1)
				(type default)
			)
			(layer "F.Fab")
		)
		(fp_line
			(start -0.750062 -1.560068)
			(end 0.750062 -1.560068)
			(stroke
				(width 0.1)
				(type default)
			)
			(layer "F.Fab")
		)
		(fp_line
			(start 0.750062 -1.560068)
			(end 0.750062 1.560068)
			(stroke
				(width 0.1)
				(type default)
			)
			(layer "F.Fab")
		)
		(pad "D" smd rect
			(at 1.100074 0 180)
			(size 1.016 1.4224)
			(layers "F.Cu" "F.Mask" "F.Paste")
			(net "SSD8_LED_ISO_N")
		)
		(pad "G" smd rect
			(at -1.100074 -0.94996 180)
			(size 1.016 1.4224)
			(layers "F.Cu" "F.Mask" "F.Paste")
			(net "SSD8_LED_R")
		)
		(pad "S" smd rect
			(at -1.100074 0.94996 180)
			(size 1.016 1.4224)
			(layers "F.Cu" "F.Mask" "F.Paste")
			(net "GND")
		)
	)
	(footprint ""
		(layer "F.Cu")
		(at 439.679334 -300.641004 -90)
		(property "Reference" "R3991"
			(at 0 0 270)
			(layer "F.SilkS")
			(hide yes)
			(effects
				(font
					(size 1.27 1.27)
				)
			)
		)
		(property "Value" ""
			(at 0 0 270)
			(layer "F.Fab")
			(effects
				(font
					(size 1.27 1.27)
				)
			)
		)
		(duplicate_pad_numbers_are_jumpers no)
		(fp_line
			(start -0.7874 0.4064)
			(end -0.7874 -0.4064)
			(stroke
				(width 0.1524)
				(type default)
			)
			(layer "F.SilkS")
		)
		(fp_line
			(start 0.7874 0.4064)
			(end -0.7874 0.4064)
			(stroke
				(width 0.1524)
				(type default)
			)
			(layer "F.SilkS")
		)
		(fp_line
			(start -0.7874 -0.4064)
			(end 0.7874 -0.4064)
			(stroke
				(width 0.1524)
				(type default)
			)
			(layer "F.SilkS")
		)
		(fp_line
			(start 0.7874 -0.4064)
			(end 0.7874 0.4064)
			(stroke
				(width 0.1524)
				(type default)
			)
			(layer "F.SilkS")
		)
		(fp_line
			(start -0.67945 0.3048)
			(end -0.67945 -0.305054)
			(stroke
				(width 0.1)
				(type default)
			)
			(layer "F.Fab")
		)
		(fp_line
			(start -0.12065 0.3048)
			(end -0.67945 0.3048)
			(stroke
				(width 0.1)
				(type default)
			)
			(layer "F.Fab")
		)
		(fp_line
			(start 0.120396 0.3048)
			(end 0.120396 0.2794)
			(stroke
				(width 0.1)
				(type default)
			)
			(layer "F.Fab")
		)
		(fp_line
			(start 0.67945 0.3048)
			(end 0.120396 0.3048)
			(stroke
				(width 0.1)
				(type default)
			)
			(layer "F.Fab")
		)
		(fp_line
			(start -0.12065 0.2794)
			(end -0.12065 0.3048)
			(stroke
				(width 0.1)
				(type default)
			)
			(layer "F.Fab")
		)
		(fp_line
			(start 0.120396 0.2794)
			(end -0.12065 0.2794)
			(stroke
				(width 0.1)
				(type default)
			)
			(layer "F.Fab")
		)
		(fp_line
			(start -0.12065 -0.2794)
			(end 0.12065 -0.2794)
			(stroke
				(width 0.1)
				(type default)
			)
			(layer "F.Fab")
		)
		(fp_line
			(start 0.12065 -0.2794)
			(end 0.12065 -0.3048)
			(stroke
				(width 0.1)
				(type default)
			)
			(layer "F.Fab")
		)
		(fp_line
			(start 0.12065 -0.3048)
			(end 0.67945 -0.3048)
			(stroke
				(width 0.1)
				(type default)
			)
			(layer "F.Fab")
		)
		(fp_line
			(start 0.67945 -0.3048)
			(end 0.67945 0.3048)
			(stroke
				(width 0.1)
				(type default)
			)
			(layer "F.Fab")
		)
		(fp_line
			(start -0.67945 -0.305054)
			(end -0.12065 -0.305054)
			(stroke
				(width 0.1)
				(type default)
			)
			(layer "F.Fab")
		)
		(fp_line
			(start -0.12065 -0.305054)
			(end -0.12065 -0.2794)
			(stroke
				(width 0.1)
				(type default)
			)
			(layer "F.Fab")
		)
		(pad "1" smd circle
			(at -0.40005 0 270)
			(size 0 0)
			(layers "F.Cu" "F.Mask" "F.Paste")
			(net "I2C0_PEX3_SCL")
		)
		(pad "2" smd circle
			(at 0.40005 0 270)
			(size 0 0)
			(layers "F.Cu" "F.Mask" "F.Paste")
			(net "I2C_PEX3_HOST_SCL")
		)
	)
	(footprint ""
		(layer "F.Cu")
		(at 109.581696 -92.333572 -90)
		(property "Reference" "R1151"
			(at 0 0 270)
			(layer "F.SilkS")
			(hide yes)
			(effects
				(font
					(size 1.27 1.27)
				)
			)
		)
		(property "Value" ""
			(at 0 0 270)
			(layer "F.Fab")
			(effects
				(font
					(size 1.27 1.27)
				)
			)
		)
		(duplicate_pad_numbers_are_jumpers no)
		(fp_line
			(start 0.7874 0.4064)
			(end -0.7874 0.4064)
			(stroke
				(width 0.1524)
				(type default)
			)
			(layer "F.SilkS")
		)
		(fp_line
			(start -0.67945 0.3048)
			(end -0.67945 -0.305054)
			(stroke
				(width 0.1)
				(type default)
			)
			(layer "F.Fab")
		)
		(fp_line
			(start -0.12065 0.3048)
			(end -0.67945 0.3048)
			(stroke
				(width 0.1)
				(type default)
			)
			(layer "F.Fab")
		)
		(fp_line
			(start 0.120396 0.3048)
			(end 0.120396 0.2794)
			(stroke
				(width 0.1)
				(type default)
			)
			(layer "F.Fab")
		)
		(fp_line
			(start 0.67945 0.3048)
			(end 0.120396 0.3048)
			(stroke
				(width 0.1)
				(type default)
			)
			(layer "F.Fab")
		)
		(fp_line
			(start -0.12065 0.2794)
			(end -0.12065 0.3048)
			(stroke
				(width 0.1)
				(type default)
			)
			(layer "F.Fab")
		)
		(fp_line
			(start 0.120396 0.2794)
			(end -0.12065 0.2794)
			(stroke
				(width 0.1)
				(type default)
			)
			(layer "F.Fab")
		)
		(fp_line
			(start -0.12065 -0.2794)
			(end 0.12065 -0.2794)
			(stroke
				(width 0.1)
				(type default)
			)
			(layer "F.Fab")
		)
		(fp_line
			(start 0.12065 -0.2794)
			(end 0.12065 -0.3048)
			(stroke
				(width 0.1)
				(type default)
			)
			(layer "F.Fab")
		)
		(fp_line
			(start 0.12065 -0.3048)
			(end 0.67945 -0.3048)
			(stroke
				(width 0.1)
				(type default)
			)
			(layer "F.Fab")
		)
		(fp_line
			(start 0.67945 -0.3048)
			(end 0.67945 0.3048)
			(stroke
				(width 0.1)
				(type default)
			)
			(layer "F.Fab")
		)
		(fp_line
			(start -0.67945 -0.305054)
			(end -0.12065 -0.305054)
			(stroke
				(width 0.1)
				(type default)
			)
			(layer "F.Fab")
		)
		(fp_line
			(start -0.12065 -0.305054)
			(end -0.12065 -0.2794)
			(stroke
				(width 0.1)
				(type default)
			)
			(layer "F.Fab")
		)
		(pad "1" smd circle
			(at -0.40005 0 270)
			(size 0 0)
			(layers "F.Cu" "F.Mask" "F.Paste")
			(net "CLK_100M_DB800ZL_SSD7_R_DN")
		)
		(pad "2" smd circle
			(at 0.40005 0 270)
			(size 0 0)
			(layers "F.Cu" "F.Mask" "F.Paste")
			(net "CLK_100M_DB800ZL_SSD7_DN")
		)
	)
	(footprint ""
		(layer "F.Cu")
		(at 104.848406 -225.945954 180)
		(property "Reference" "PC288"
			(at 0 0 180)
			(layer "F.SilkS")
			(hide yes)
			(effects
				(font
					(size 1.27 1.27)
				)
			)
		)
		(property "Value" ""
			(at 0 0 180)
			(layer "F.Fab")
			(effects
				(font
					(size 1.27 1.27)
				)
			)
		)
		(duplicate_pad_numbers_are_jumpers no)
		(fp_line
			(start 0.7874 0.4064)
			(end -0.7874 0.4064)
			(stroke
				(width 0.1524)
				(type default)
			)
			(layer "F.SilkS")
		)
		(fp_line
			(start 0.7874 -0.4064)
			(end 0.7874 0.4064)
			(stroke
				(width 0.1524)
				(type default)
			)
			(layer "F.SilkS")
		)
		(fp_line
			(start -0.7874 0.4064)
			(end -0.7874 -0.4064)
			(stroke
				(width 0.1524)
				(type default)
			)
			(layer "F.SilkS")
		)
		(fp_line
			(start -0.7874 -0.4064)
			(end 0.7874 -0.4064)
			(stroke
				(width 0.1524)
				(type default)
			)
			(layer "F.SilkS")
		)
		(fp_line
			(start 0.67945 0.3048)
			(end 0.120396 0.3048)
			(stroke
				(width 0.1)
				(type default)
			)
			(layer "F.Fab")
		)
		(fp_line
			(start 0.67945 -0.3048)
			(end 0.67945 0.3048)
			(stroke
				(width 0.1)
				(type default)
			)
			(layer "F.Fab")
		)
		(fp_line
			(start 0.12065 -0.2794)
			(end 0.12065 -0.3048)
			(stroke
				(width 0.1)
				(type default)
			)
			(layer "F.Fab")
		)
		(fp_line
			(start 0.12065 -0.3048)
			(end 0.67945 -0.3048)
			(stroke
				(width 0.1)
				(type default)
			)
			(layer "F.Fab")
		)
		(fp_line
			(start 0.120396 0.3048)
			(end 0.120396 0.2794)
			(stroke
				(width 0.1)
				(type default)
			)
			(layer "F.Fab")
		)
		(fp_line
			(start 0.120396 0.2794)
			(end -0.12065 0.2794)
			(stroke
				(width 0.1)
				(type default)
			)
			(layer "F.Fab")
		)
		(fp_line
			(start -0.12065 0.3048)
			(end -0.67945 0.3048)
			(stroke
				(width 0.1)
				(type default)
			)
			(layer "F.Fab")
		)
		(fp_line
			(start -0.12065 0.2794)
			(end -0.12065 0.3048)
			(stroke
				(width 0.1)
				(type default)
			)
			(layer "F.Fab")
		)
		(fp_line
			(start -0.12065 -0.2794)
			(end 0.12065 -0.2794)
			(stroke
				(width 0.1)
				(type default)
			)
			(layer "F.Fab")
		)
		(fp_line
			(start -0.12065 -0.305054)
			(end -0.12065 -0.2794)
			(stroke
				(width 0.1)
				(type default)
			)
			(layer "F.Fab")
		)
		(fp_line
			(start -0.67945 0.3048)
			(end -0.67945 -0.305054)
			(stroke
				(width 0.1)
				(type default)
			)
			(layer "F.Fab")
		)
		(fp_line
			(start -0.67945 -0.305054)
			(end -0.12065 -0.305054)
			(stroke
				(width 0.1)
				(type default)
			)
			(layer "F.Fab")
		)
		(pad "1" smd circle
			(at -0.40005 0 180)
			(size 0 0)
			(layers "F.Cu" "F.Mask" "F.Paste")
			(net "SW_P12V_P1V8_PEX_FLT")
		)
		(pad "2" smd circle
			(at 0.40005 0 180)
			(size 0 0)
			(layers "F.Cu" "F.Mask" "F.Paste")
			(net "GND")
		)
	)
	(footprint ""
		(layer "F.Cu")
		(at 201.871834 -24.807418)
		(property "Reference" "R431"
			(at 0 0 0)
			(layer "F.SilkS")
			(hide yes)
			(effects
				(font
					(size 1.27 1.27)
				)
			)
		)
		(property "Value" ""
			(at 0 0 0)
			(layer "F.Fab")
			(effects
				(font
					(size 1.27 1.27)
				)
			)
		)
		(duplicate_pad_numbers_are_jumpers no)
		(fp_line
			(start -0.7874 -0.4064)
			(end 0.7874 -0.4064)
			(stroke
				(width 0.1524)
				(type default)
			)
			(layer "F.SilkS")
		)
		(fp_line
			(start -0.7874 0.4064)
			(end -0.7874 -0.4064)
			(stroke
				(width 0.1524)
				(type default)
			)
			(layer "F.SilkS")
		)
		(fp_line
			(start 0.7874 -0.4064)
			(end 0.7874 0.4064)
			(stroke
				(width 0.1524)
				(type default)
			)
			(layer "F.SilkS")
		)
		(fp_line
			(start 0.7874 0.4064)
			(end -0.7874 0.4064)
			(stroke
				(width 0.1524)
				(type default)
			)
			(layer "F.SilkS")
		)
		(fp_line
			(start -0.67945 -0.305054)
			(end -0.12065 -0.305054)
			(stroke
				(width 0.1)
				(type default)
			)
			(layer "F.Fab")
		)
		(fp_line
			(start -0.67945 0.3048)
			(end -0.67945 -0.305054)
			(stroke
				(width 0.1)
				(type default)
			)
			(layer "F.Fab")
		)
		(fp_line
			(start -0.12065 -0.305054)
			(end -0.12065 -0.2794)
			(stroke
				(width 0.1)
				(type default)
			)
			(layer "F.Fab")
		)
		(fp_line
			(start -0.12065 -0.2794)
			(end 0.12065 -0.2794)
			(stroke
				(width 0.1)
				(type default)
			)
			(layer "F.Fab")
		)
		(fp_line
			(start -0.12065 0.2794)
			(end -0.12065 0.3048)
			(stroke
				(width 0.1)
				(type default)
			)
			(layer "F.Fab")
		)
		(fp_line
			(start -0.12065 0.3048)
			(end -0.67945 0.3048)
			(stroke
				(width 0.1)
				(type default)
			)
			(layer "F.Fab")
		)
		(fp_line
			(start 0.120396 0.2794)
			(end -0.12065 0.2794)
			(stroke
				(width 0.1)
				(type default)
			)
			(layer "F.Fab")
		)
		(fp_line
			(start 0.120396 0.3048)
			(end 0.120396 0.2794)
			(stroke
				(width 0.1)
				(type default)
			)
			(layer "F.Fab")
		)
		(fp_line
			(start 0.12065 -0.3048)
			(end 0.67945 -0.3048)
			(stroke
				(width 0.1)
				(type default)
			)
			(layer "F.Fab")
		)
		(fp_line
			(start 0.12065 -0.2794)
			(end 0.12065 -0.3048)
			(stroke
				(width 0.1)
				(type default)
			)
			(layer "F.Fab")
		)
		(fp_line
			(start 0.67945 -0.3048)
			(end 0.67945 0.3048)
			(stroke
				(width 0.1)
				(type default)
			)
			(layer "F.Fab")
		)
		(fp_line
			(start 0.67945 0.3048)
			(end 0.120396 0.3048)
			(stroke
				(width 0.1)
				(type default)
			)
			(layer "F.Fab")
		)
		(pad "1" smd circle
			(at -0.40005 0)
			(size 0 0)
			(layers "F.Cu" "F.Mask" "F.Paste")
			(net "P3V3_SSD7")
		)
		(pad "2" smd circle
			(at 0.40005 0)
			(size 0 0)
			(layers "F.Cu" "F.Mask" "F.Paste")
			(net "PU_CLKREQ7")
		)
	)
)
